# SCM (Grand Teton) — schematic netlist excerpt (pin names and nets, part order shuffled) for the footprints in the layout excerpt that follows; sources: Cadence DE-HDL packaged netlist, KiCad conversion of 12092022_DA0F0TMDCD0_F0T_Management_Board_D_brd_V3_OCP.brd

R70  Q_RES  33.2 1% CHIP  pkg 0402LF  page 13 : A = RST_PCA9548_SENSOR_R_N ; B = RST_PCA9548_SENSOR_N
C161  Q_CAP  1UF 25V 10% X6S  pkg C0402  page 22 : A = RST_BMC_SELF_HW_D ; B = RST_BMC_SELF_HW_D_C

(kicad_pcb
	(version 20260206)
	(generator "pcbnew")
	(generator_version "10.0")
	(general
		(thickness 1.6)
		(legacy_teardrops no)
	)
	(paper "A4")
	(title_block
		(title "12092022_DA0F0TMDCD0_F0T_Management_Board_D_brd_V3_OCP.brd")
		(comment 1 "Grand Teton / footprints 396-397 of 1440")
	)
	(layers
		(0 "F.Cu" signal "TOP")
		(4 "In1.Cu" signal "GND")
		(6 "In2.Cu" signal "IN1")
		(8 "In3.Cu" signal "GND1")
		(10 "In4.Cu" signal "IN2")
		(12 "In5.Cu" signal "VCC")
		(14 "In6.Cu" signal "VCC1")
		(16 "In7.Cu" signal "IN3")
		(18 "In8.Cu" signal "GND2")
		(20 "In9.Cu" signal "IN4")
		(22 "In10.Cu" signal "GND3")
		(2 "B.Cu" signal "BOTTOM")
		(9 "F.Adhes" user "F.Adhesive")
		(11 "B.Adhes" user "B.Adhesive")
		(13 "F.Paste" user "Package Geometry/Pastemask Top")
		(15 "B.Paste" user "Package Geometry/Pastemask Bottom")
		(5 "F.SilkS" user "Ref Des/Silkscreen Top")
		(7 "B.SilkS" user "Ref Des/Silkscreen Bottom")
		(1 "F.Mask" user "Board Geometry/Soldermask Top")
		(3 "B.Mask" user "Board Geometry/Soldermask Bottom")
		(17 "Dwgs.User" user "User.Drawings")
		(19 "Cmts.User" user "User.Comments")
		(21 "Eco1.User" user "User.Eco1")
		(23 "Eco2.User" user "User.Eco2")
		(25 "Edge.Cuts" user "Board Geometry/Outline")
		(27 "Margin" user)
		(31 "F.CrtYd" user "Package Geometry/Place Bound Top")
		(29 "B.CrtYd" user "Package Geometry/Place Bound Bottom")
		(35 "F.Fab" user "Ref Des/Assembly Top")
		(33 "B.Fab" user "Ref Des/Assembly Bottom")
	)
	(footprint ""
		(layer "F.Cu")
		(at 33.7566 -46.4058 -90)
		(property "Reference" "R70"
			(at 0 0 270)
			(layer "F.SilkS")
			(hide yes)
			(effects
				(font
					(size 1.27 1.27)
				)
			)
		)
		(property "Value" ""
			(at 0 0 270)
			(layer "F.Fab")
			(effects
				(font
					(size 1.27 1.27)
				)
			)
		)
		(duplicate_pad_numbers_are_jumpers no)
		(fp_line
			(start -0.7874 0.4064)
			(end -0.7874 -0.4064)
			(stroke
				(width 0.1524)
				(type default)
			)
			(layer "F.SilkS")
		)
		(fp_line
			(start 0.7874 0.4064)
			(end -0.7874 0.4064)
			(stroke
				(width 0.1524)
				(type default)
			)
			(layer "F.SilkS")
		)
		(fp_line
			(start -0.7874 -0.4064)
			(end 0.7874 -0.4064)
			(stroke
				(width 0.1524)
				(type default)
			)
			(layer "F.SilkS")
		)
		(fp_line
			(start 0.7874 -0.4064)
			(end 0.7874 0.4064)
			(stroke
				(width 0.1524)
				(type default)
			)
			(layer "F.SilkS")
		)
		(fp_line
			(start -0.67945 0.3048)
			(end -0.67945 -0.305054)
			(stroke
				(width 0.1)
				(type default)
			)
			(layer "F.Fab")
		)
		(fp_line
			(start -0.12065 0.3048)
			(end -0.67945 0.3048)
			(stroke
				(width 0.1)
				(type default)
			)
			(layer "F.Fab")
		)
		(fp_line
			(start 0.120396 0.3048)
			(end 0.120396 0.2794)
			(stroke
				(width 0.1)
				(type default)
			)
			(layer "F.Fab")
		)
		(fp_line
			(start 0.67945 0.3048)
			(end 0.120396 0.3048)
			(stroke
				(width 0.1)
				(type default)
			)
			(layer "F.Fab")
		)
		(fp_line
			(start -0.12065 0.2794)
			(end -0.12065 0.3048)
			(stroke
				(width 0.1)
				(type default)
			)
			(layer "F.Fab")
		)
		(fp_line
			(start 0.120396 0.2794)
			(end -0.12065 0.2794)
			(stroke
				(width 0.1)
				(type default)
			)
			(layer "F.Fab")
		)
		(fp_line
			(start -0.12065 -0.2794)
			(end 0.12065 -0.2794)
			(stroke
				(width 0.1)
				(type default)
			)
			(layer "F.Fab")
		)
		(fp_line
			(start 0.12065 -0.2794)
			(end 0.12065 -0.3048)
			(stroke
				(width 0.1)
				(type default)
			)
			(layer "F.Fab")
		)
		(fp_line
			(start 0.12065 -0.3048)
			(end 0.67945 -0.3048)
			(stroke
				(width 0.1)
				(type default)
			)
			(layer "F.Fab")
		)
		(fp_line
			(start 0.67945 -0.3048)
			(end 0.67945 0.3048)
			(stroke
				(width 0.1)
				(type default)
			)
			(layer "F.Fab")
		)
		(fp_line
			(start -0.67945 -0.305054)
			(end -0.12065 -0.305054)
			(stroke
				(width 0.1)
				(type default)
			)
			(layer "F.Fab")
		)
		(fp_line
			(start -0.12065 -0.305054)
			(end -0.12065 -0.2794)
			(stroke
				(width 0.1)
				(type default)
			)
			(layer "F.Fab")
		)
		(pad "1" smd circle
			(at -0.40005 0 270)
			(size 0 0)
			(layers "F.Cu" "F.Mask" "F.Paste")
			(net "RST_PCA9548_SENSOR_R_N")
		)
		(pad "2" smd circle
			(at 0.40005 0 270)
			(size 0 0)
			(layers "F.Cu" "F.Mask" "F.Paste")
			(net "RST_PCA9548_SENSOR_N")
		)
	)
	(footprint ""
		(layer "F.Cu")
		(at 23.61946 -108.71708 180)
		(property "Reference" "C161"
			(at 0 0 180)
			(layer "F.SilkS")
			(hide yes)
			(effects
				(font
					(size 1.27 1.27)
				)
			)
		)
		(property "Value" ""
			(at 0 0 180)
			(layer "F.Fab")
			(effects
				(font
					(size 1.27 1.27)
				)
			)
		)
		(duplicate_pad_numbers_are_jumpers no)
		(fp_line
			(start 0.7874 0.4064)
			(end -0.7874 0.4064)
			(stroke
				(width 0.1524)
				(type default)
			)
			(layer "F.SilkS")
		)
		(fp_line
			(start 0.7874 -0.4064)
			(end 0.7874 0.4064)
			(stroke
				(width 0.1524)
				(type default)
			)
			(layer "F.SilkS")
		)
		(fp_line
			(start -0.7874 0.4064)
			(end -0.7874 -0.4064)
			(stroke
				(width 0.1524)
				(type default)
			)
			(layer "F.SilkS")
		)
		(fp_line
			(start -0.7874 -0.4064)
			(end 0.7874 -0.4064)
			(stroke
				(width 0.1524)
				(type default)
			)
			(layer "F.SilkS")
		)
		(fp_line
			(start 0.67945 0.3048)
			(end 0.120396 0.3048)
			(stroke
				(width 0.1)
				(type default)
			)
			(layer "F.Fab")
		)
		(fp_line
			(start 0.67945 -0.3048)
			(end 0.67945 0.3048)
			(stroke
				(width 0.1)
				(type default)
			)
			(layer "F.Fab")
		)
		(fp_line
			(start 0.12065 -0.2794)
			(end 0.12065 -0.3048)
			(stroke
				(width 0.1)
				(type default)
			)
			(layer "F.Fab")
		)
		(fp_line
			(start 0.12065 -0.3048)
			(end 0.67945 -0.3048)
			(stroke
				(width 0.1)
				(type default)
			)
			(layer "F.Fab")
		)
		(fp_line
			(start 0.120396 0.3048)
			(end 0.120396 0.2794)
			(stroke
				(width 0.1)
				(type default)
			)
			(layer "F.Fab")
		)
		(fp_line
			(start 0.120396 0.2794)
			(end -0.12065 0.2794)
			(stroke
				(width 0.1)
				(type default)
			)
			(layer "F.Fab")
		)
		(fp_line
			(start -0.12065 0.3048)
			(end -0.67945 0.3048)
			(stroke
				(width 0.1)
				(type default)
			)
			(layer "F.Fab")
		)
		(fp_line
			(start -0.12065 0.2794)
			(end -0.12065 0.3048)
			(stroke
				(width 0.1)
				(type default)
			)
			(layer "F.Fab")
		)
		(fp_line
			(start -0.12065 -0.2794)
			(end 0.12065 -0.2794)
			(stroke
				(width 0.1)
				(type default)
			)
			(layer "F.Fab")
		)
		(fp_line
			(start -0.12065 -0.305054)
			(end -0.12065 -0.2794)
			(stroke
				(width 0.1)
				(type default)
			)
			(layer "F.Fab")
		)
		(fp_line
			(start -0.67945 0.3048)
			(end -0.67945 -0.305054)
			(stroke
				(width 0.1)
				(type default)
			)
			(layer "F.Fab")
		)
		(fp_line
			(start -0.67945 -0.305054)
			(end -0.12065 -0.305054)
			(stroke
				(width 0.1)
				(type default)
			)
			(layer "F.Fab")
		)
		(pad "1" smd circle
			(at -0.40005 0 180)
			(size 0 0)
			(layers "F.Cu" "F.Mask" "F.Paste")
			(net "RST_BMC_SELF_HW_D")
		)
		(pad "2" smd circle
			(at 0.40005 0 180)
			(size 0 0)
			(layers "F.Cu" "F.Mask" "F.Paste")
			(net "RST_BMC_SELF_HW_D_C")
		)
	)
)
